(kicad_pcb
	(version 20260206)
	(generator "pcbnew")
	(generator_version "10.0")
	(general
		(thickness 1.6)
		(legacy_teardrops no)
	)
	(paper "A4")
	(title_block
		(title "01162023_DA0F0TEBIF0_F0T_Expander_BD_F_brd_V02_OCP.brd")
		(comment 1 "Grand Teton / footprints 7194-7200 of 9728")
	)
	(layers
		(0 "F.Cu" signal "TOP")
		(4 "In1.Cu" signal "GND")
		(6 "In2.Cu" signal "VCC")
		(8 "In3.Cu" signal "VCC1")
		(10 "In4.Cu" signal "GND1")
		(12 "In5.Cu" signal "IN1")
		(14 "In6.Cu" signal "GND2")
		(16 "In7.Cu" signal "IN2")
		(18 "In8.Cu" signal "GND3")
		(20 "In9.Cu" signal "IN3")
		(22 "In10.Cu" signal "GND4")
		(24 "In11.Cu" signal "IN4")
		(26 "In12.Cu" signal "GND5")
		(28 "In13.Cu" signal "IN5")
		(30 "In14.Cu" signal "GND6")
		(32 "In15.Cu" signal "IN6")
		(34 "In16.Cu" signal "GND7")
		(2 "B.Cu" signal "BOTTOM")
		(9 "F.Adhes" user "F.Adhesive")
		(11 "B.Adhes" user "B.Adhesive")
		(13 "F.Paste" user "Package Geometry/Pastemask Top")
		(15 "B.Paste" user "Package Geometry/Pastemask Bottom")
		(5 "F.SilkS" user "Ref Des/Silkscreen Top")
		(7 "B.SilkS" user "Ref Des/Silkscreen Bottom")
		(1 "F.Mask" user "Board Geometry/Soldermask Top")
		(3 "B.Mask" user "Board Geometry/Soldermask Bottom")
		(17 "Dwgs.User" user "User.Drawings")
		(19 "Cmts.User" user "User.Comments")
		(21 "Eco1.User" user "User.Eco1")
		(23 "Eco2.User" user "User.Eco2")
		(25 "Edge.Cuts" user "Board Geometry/Outline")
		(27 "Margin" user)
		(31 "F.CrtYd" user "Package Geometry/Place Bound Top")
		(29 "B.CrtYd" user "Package Geometry/Place Bound Bottom")
		(35 "F.Fab" user "Ref Des/Assembly Top")
		(33 "B.Fab" user "Ref Des/Assembly Bottom")
	)
	(footprint ""
		(layer "B.Cu")
		(at 148.285962 -237.948978)
		(property "Reference" "C4422"
			(at 0 0 0)
			(layer "B.SilkS")
			(hide yes)
			(effects
				(font
					(size 1.27 1.27)
				)
				(justify mirror)
			)
		)
		(property "Value" ""
			(at 0 0 0)
			(layer "B.Fab")
			(effects
				(font
					(size 1.27 1.27)
				)
				(justify mirror)
			)
		)
		(duplicate_pad_numbers_are_jumpers no)
		(fp_line
			(start -0.7874 -0.4064)
			(end -0.7874 0.4064)
			(stroke
				(width 0.1524)
				(type default)
			)
			(layer "B.SilkS")
		)
		(fp_line
			(start -0.7874 0.4064)
			(end 0.7874 0.4064)
			(stroke
				(width 0.1524)
				(type default)
			)
			(layer "B.SilkS")
		)
		(fp_line
			(start 0.7874 -0.4064)
			(end -0.7874 -0.4064)
			(stroke
				(width 0.1524)
				(type default)
			)
			(layer "B.SilkS")
		)
		(fp_line
			(start 0.7874 0.4064)
			(end 0.7874 -0.4064)
			(stroke
				(width 0.1524)
				(type default)
			)
			(layer "B.SilkS")
		)
		(fp_line
			(start -0.67945 -0.3048)
			(end -0.67945 0.3048)
			(stroke
				(width 0.1)
				(type default)
			)
			(layer "B.Fab")
		)
		(fp_line
			(start -0.67945 0.3048)
			(end -0.120396 0.3048)
			(stroke
				(width 0.1)
				(type default)
			)
			(layer "B.Fab")
		)
		(fp_line
			(start -0.12065 -0.3048)
			(end -0.67945 -0.3048)
			(stroke
				(width 0.1)
				(type default)
			)
			(layer "B.Fab")
		)
		(fp_line
			(start -0.12065 -0.2794)
			(end -0.12065 -0.3048)
			(stroke
				(width 0.1)
				(type default)
			)
			(layer "B.Fab")
		)
		(fp_line
			(start -0.120396 0.2794)
			(end 0.12065 0.2794)
			(stroke
				(width 0.1)
				(type default)
			)
			(layer "B.Fab")
		)
		(fp_line
			(start -0.120396 0.3048)
			(end -0.120396 0.2794)
			(stroke
				(width 0.1)
				(type default)
			)
			(layer "B.Fab")
		)
		(fp_line
			(start 0.12065 -0.305054)
			(end 0.12065 -0.2794)
			(stroke
				(width 0.1)
				(type default)
			)
			(layer "B.Fab")
		)
		(fp_line
			(start 0.12065 -0.2794)
			(end -0.12065 -0.2794)
			(stroke
				(width 0.1)
				(type default)
			)
			(layer "B.Fab")
		)
		(fp_line
			(start 0.12065 0.2794)
			(end 0.12065 0.3048)
			(stroke
				(width 0.1)
				(type default)
			)
			(layer "B.Fab")
		)
		(fp_line
			(start 0.12065 0.3048)
			(end 0.67945 0.3048)
			(stroke
				(width 0.1)
				(type default)
			)
			(layer "B.Fab")
		)
		(fp_line
			(start 0.67945 -0.305054)
			(end 0.12065 -0.305054)
			(stroke
				(width 0.1)
				(type default)
			)
			(layer "B.Fab")
		)
		(fp_line
			(start 0.67945 0.3048)
			(end 0.67945 -0.305054)
			(stroke
				(width 0.1)
				(type default)
			)
			(layer "B.Fab")
		)
		(pad "1" smd circle
			(at 0.40005 0 180)
			(size 0 0)
			(layers "B.Cu" "B.Mask" "B.Paste")
			(net "P1V8_PLL0_PEX1")
		)
		(pad "2" smd circle
			(at -0.40005 0 180)
			(size 0 0)
			(layers "B.Cu" "B.Mask" "B.Paste")
			(net "GND")
		)
	)
	(footprint ""
		(layer "B.Cu")
		(at 252.0188 -347.7768 180)
		(property "Reference" "PR7161"
			(at 0 0 0)
			(layer "B.SilkS")
			(hide yes)
			(effects
				(font
					(size 1.27 1.27)
				)
				(justify mirror)
			)
		)
		(property "Value" ""
			(at 0 0 0)
			(layer "B.Fab")
			(effects
				(font
					(size 1.27 1.27)
				)
				(justify mirror)
			)
		)
		(duplicate_pad_numbers_are_jumpers no)
		(fp_line
			(start 0.7874 0.4064)
			(end 0.7874 -0.4064)
			(stroke
				(width 0.1524)
				(type default)
			)
			(layer "B.SilkS")
		)
		(fp_line
			(start 0.7874 -0.4064)
			(end -0.7874 -0.4064)
			(stroke
				(width 0.1524)
				(type default)
			)
			(layer "B.SilkS")
		)
		(fp_line
			(start -0.7874 0.4064)
			(end 0.7874 0.4064)
			(stroke
				(width 0.1524)
				(type default)
			)
			(layer "B.SilkS")
		)
		(fp_line
			(start -0.7874 -0.4064)
			(end -0.7874 0.4064)
			(stroke
				(width 0.1524)
				(type default)
			)
			(layer "B.SilkS")
		)
		(fp_line
			(start 0.67945 0.3048)
			(end 0.67945 -0.305054)
			(stroke
				(width 0.1)
				(type default)
			)
			(layer "B.Fab")
		)
		(fp_line
			(start 0.67945 -0.305054)
			(end 0.12065 -0.305054)
			(stroke
				(width 0.1)
				(type default)
			)
			(layer "B.Fab")
		)
		(fp_line
			(start 0.12065 0.3048)
			(end 0.67945 0.3048)
			(stroke
				(width 0.1)
				(type default)
			)
			(layer "B.Fab")
		)
		(fp_line
			(start 0.12065 0.2794)
			(end 0.12065 0.3048)
			(stroke
				(width 0.1)
				(type default)
			)
			(layer "B.Fab")
		)
		(fp_line
			(start 0.12065 -0.2794)
			(end -0.12065 -0.2794)
			(stroke
				(width 0.1)
				(type default)
			)
			(layer "B.Fab")
		)
		(fp_line
			(start 0.12065 -0.305054)
			(end 0.12065 -0.2794)
			(stroke
				(width 0.1)
				(type default)
			)
			(layer "B.Fab")
		)
		(fp_line
			(start -0.120396 0.3048)
			(end -0.120396 0.2794)
			(stroke
				(width 0.1)
				(type default)
			)
			(layer "B.Fab")
		)
		(fp_line
			(start -0.120396 0.2794)
			(end 0.12065 0.2794)
			(stroke
				(width 0.1)
				(type default)
			)
			(layer "B.Fab")
		)
		(fp_line
			(start -0.12065 -0.2794)
			(end -0.12065 -0.3048)
			(stroke
				(width 0.1)
				(type default)
			)
			(layer "B.Fab")
		)
		(fp_line
			(start -0.12065 -0.3048)
			(end -0.67945 -0.3048)
			(stroke
				(width 0.1)
				(type default)
			)
			(layer "B.Fab")
		)
		(fp_line
			(start -0.67945 0.3048)
			(end -0.120396 0.3048)
			(stroke
				(width 0.1)
				(type default)
			)
			(layer "B.Fab")
		)
		(fp_line
			(start -0.67945 -0.3048)
			(end -0.67945 0.3048)
			(stroke
				(width 0.1)
				(type default)
			)
			(layer "B.Fab")
		)
		(pad "1" smd circle
			(at 0.40005 0)
			(size 0 0)
			(layers "B.Cu" "B.Mask" "B.Paste")
			(net "IRQ_HSC_FAULT_R_N")
		)
		(pad "2" smd circle
			(at -0.40005 0)
			(size 0 0)
			(layers "B.Cu" "B.Mask" "B.Paste")
			(net "FM_HSC_FAULT_N")
		)
	)
	(footprint ""
		(layer "B.Cu")
		(at 222.212154 -196.991732 90)
		(property "Reference" "R463"
			(at 0 0 90)
			(layer "B.SilkS")
			(hide yes)
			(effects
				(font
					(size 1.27 1.27)
				)
				(justify mirror)
			)
		)
		(property "Value" ""
			(at 0 0 90)
			(layer "B.Fab")
			(effects
				(font
					(size 1.27 1.27)
				)
				(justify mirror)
			)
		)
		(duplicate_pad_numbers_are_jumpers no)
		(fp_line
			(start 0.7874 -0.4064)
			(end -0.7874 -0.4064)
			(stroke
				(width 0.1524)
				(type default)
			)
			(layer "B.SilkS")
		)
		(fp_line
			(start -0.7874 -0.4064)
			(end -0.7874 0.4064)
			(stroke
				(width 0.1524)
				(type default)
			)
			(layer "B.SilkS")
		)
		(fp_line
			(start 0.7874 0.4064)
			(end 0.7874 -0.4064)
			(stroke
				(width 0.1524)
				(type default)
			)
			(layer "B.SilkS")
		)
		(fp_line
			(start -0.7874 0.4064)
			(end 0.7874 0.4064)
			(stroke
				(width 0.1524)
				(type default)
			)
			(layer "B.SilkS")
		)
		(fp_line
			(start 0.67945 -0.305054)
			(end 0.12065 -0.305054)
			(stroke
				(width 0.1)
				(type default)
			)
			(layer "B.Fab")
		)
		(fp_line
			(start 0.12065 -0.305054)
			(end 0.12065 -0.2794)
			(stroke
				(width 0.1)
				(type default)
			)
			(layer "B.Fab")
		)
		(fp_line
			(start -0.12065 -0.3048)
			(end -0.67945 -0.3048)
			(stroke
				(width 0.1)
				(type default)
			)
			(layer "B.Fab")
		)
		(fp_line
			(start -0.67945 -0.3048)
			(end -0.67945 0.3048)
			(stroke
				(width 0.1)
				(type default)
			)
			(layer "B.Fab")
		)
		(fp_line
			(start 0.12065 -0.2794)
			(end -0.12065 -0.2794)
			(stroke
				(width 0.1)
				(type default)
			)
			(layer "B.Fab")
		)
		(fp_line
			(start -0.12065 -0.2794)
			(end -0.12065 -0.3048)
			(stroke
				(width 0.1)
				(type default)
			)
			(layer "B.Fab")
		)
		(fp_line
			(start 0.12065 0.2794)
			(end 0.12065 0.3048)
			(stroke
				(width 0.1)
				(type default)
			)
			(layer "B.Fab")
		)
		(fp_line
			(start -0.120396 0.2794)
			(end 0.12065 0.2794)
			(stroke
				(width 0.1)
				(type default)
			)
			(layer "B.Fab")
		)
		(fp_line
			(start 0.67945 0.3048)
			(end 0.67945 -0.305054)
			(stroke
				(width 0.1)
				(type default)
			)
			(layer "B.Fab")
		)
		(fp_line
			(start 0.12065 0.3048)
			(end 0.67945 0.3048)
			(stroke
				(width 0.1)
				(type default)
			)
			(layer "B.Fab")
		)
		(fp_line
			(start -0.120396 0.3048)
			(end -0.120396 0.2794)
			(stroke
				(width 0.1)
				(type default)
			)
			(layer "B.Fab")
		)
		(fp_line
			(start -0.67945 0.3048)
			(end -0.120396 0.3048)
			(stroke
				(width 0.1)
				(type default)
			)
			(layer "B.Fab")
		)
		(pad "1" smd circle
			(at 0.40005 0 270)
			(size 0 0)
			(layers "B.Cu" "B.Mask" "B.Paste")
			(net "SPI_BIC1_MOSI_R")
		)
		(pad "2" smd circle
			(at -0.40005 0 270)
			(size 0 0)
			(layers "B.Cu" "B.Mask" "B.Paste")
			(net "SPI_BIC1_MOSI_R1")
		)
	)
	(footprint ""
		(layer "B.Cu")
		(at 329.692 -223.4692)
		(property "Reference" "R4170"
			(at 0 0 0)
			(layer "B.SilkS")
			(hide yes)
			(effects
				(font
					(size 1.27 1.27)
				)
				(justify mirror)
			)
		)
		(property "Value" ""
			(at 0 0 0)
			(layer "B.Fab")
			(effects
				(font
					(size 1.27 1.27)
				)
				(justify mirror)
			)
		)
		(duplicate_pad_numbers_are_jumpers no)
		(fp_line
			(start -0.7874 -0.4064)
			(end -0.7874 0.4064)
			(stroke
				(width 0.1524)
				(type default)
			)
			(layer "B.SilkS")
		)
		(fp_line
			(start -0.7874 0.4064)
			(end 0.7874 0.4064)
			(stroke
				(width 0.1524)
				(type default)
			)
			(layer "B.SilkS")
		)
		(fp_line
			(start 0.7874 -0.4064)
			(end -0.7874 -0.4064)
			(stroke
				(width 0.1524)
				(type default)
			)
			(layer "B.SilkS")
		)
		(fp_line
			(start 0.7874 0.4064)
			(end 0.7874 -0.4064)
			(stroke
				(width 0.1524)
				(type default)
			)
			(layer "B.SilkS")
		)
		(fp_line
			(start -0.67945 -0.3048)
			(end -0.67945 0.3048)
			(stroke
				(width 0.1)
				(type default)
			)
			(layer "B.Fab")
		)
		(fp_line
			(start -0.67945 0.3048)
			(end -0.120396 0.3048)
			(stroke
				(width 0.1)
				(type default)
			)
			(layer "B.Fab")
		)
		(fp_line
			(start -0.12065 -0.3048)
			(end -0.67945 -0.3048)
			(stroke
				(width 0.1)
				(type default)
			)
			(layer "B.Fab")
		)
		(fp_line
			(start -0.12065 -0.2794)
			(end -0.12065 -0.3048)
			(stroke
				(width 0.1)
				(type default)
			)
			(layer "B.Fab")
		)
		(fp_line
			(start -0.120396 0.2794)
			(end 0.12065 0.2794)
			(stroke
				(width 0.1)
				(type default)
			)
			(layer "B.Fab")
		)
		(fp_line
			(start -0.120396 0.3048)
			(end -0.120396 0.2794)
			(stroke
				(width 0.1)
				(type default)
			)
			(layer "B.Fab")
		)
		(fp_line
			(start 0.12065 -0.305054)
			(end 0.12065 -0.2794)
			(stroke
				(width 0.1)
				(type default)
			)
			(layer "B.Fab")
		)
		(fp_line
			(start 0.12065 -0.2794)
			(end -0.12065 -0.2794)
			(stroke
				(width 0.1)
				(type default)
			)
			(layer "B.Fab")
		)
		(fp_line
			(start 0.12065 0.2794)
			(end 0.12065 0.3048)
			(stroke
				(width 0.1)
				(type default)
			)
			(layer "B.Fab")
		)
		(fp_line
			(start 0.12065 0.3048)
			(end 0.67945 0.3048)
			(stroke
				(width 0.1)
				(type default)
			)
			(layer "B.Fab")
		)
		(fp_line
			(start 0.67945 -0.305054)
			(end 0.12065 -0.305054)
			(stroke
				(width 0.1)
				(type default)
			)
			(layer "B.Fab")
		)
		(fp_line
			(start 0.67945 0.3048)
			(end 0.67945 -0.305054)
			(stroke
				(width 0.1)
				(type default)
			)
			(layer "B.Fab")
		)
		(pad "1" smd circle
			(at 0.40005 0 180)
			(size 0 0)
			(layers "B.Cu" "B.Mask" "B.Paste")
			(net "FM_SYS_THROTTLE")
		)
		(pad "2" smd circle
			(at -0.40005 0 180)
			(size 0 0)
			(layers "B.Cu" "B.Mask" "B.Paste")
			(net "FM_SYS_THROTTLE_R")
		)
	)
	(footprint ""
		(layer "B.Cu")
		(at 348.98838 -316.868048 180)
		(property "Reference" "C4322"
			(at 0 0 0)
			(layer "B.SilkS")
			(hide yes)
			(effects
				(font
					(size 1.27 1.27)
				)
				(justify mirror)
			)
		)
		(property "Value" ""
			(at 0 0 0)
			(layer "B.Fab")
			(effects
				(font
					(size 1.27 1.27)
				)
				(justify mirror)
			)
		)
		(duplicate_pad_numbers_are_jumpers no)
		(fp_line
			(start 0.299974 0.150114)
			(end 0.299974 -0.150114)
			(stroke
				(width 0.1)
				(type default)
			)
			(layer "B.Fab")
		)
		(fp_line
			(start 0.299974 -0.150114)
			(end -0.299974 -0.150114)
			(stroke
				(width 0.1)
				(type default)
			)
			(layer "B.Fab")
		)
		(fp_line
			(start -0.299974 0.150114)
			(end 0.299974 0.150114)
			(stroke
				(width 0.1)
				(type default)
			)
			(layer "B.Fab")
		)
		(fp_line
			(start -0.299974 -0.150114)
			(end -0.299974 0.150114)
			(stroke
				(width 0.1)
				(type default)
			)
			(layer "B.Fab")
		)
		(pad "1" smd rect
			(at 0.2667 0)
			(size 0.3048 0.381)
			(layers "B.Cu" "B.Mask" "B.Paste")
			(net "P0V8_SERDES_VDDA_PEX2")
		)
		(pad "2" smd rect
			(at -0.2667 0)
			(size 0.3048 0.381)
			(layers "B.Cu" "B.Mask" "B.Paste")
			(net "GND")
		)
	)
	(footprint ""
		(layer "B.Cu")
		(at 337.221322 -303.649634 -90)
		(property "Reference" "PC168"
			(at 0 0 90)
			(layer "B.SilkS")
			(hide yes)
			(effects
				(font
					(size 1.27 1.27)
				)
				(justify mirror)
			)
		)
		(property "Value" ""
			(at 0 0 90)
			(layer "B.Fab")
			(effects
				(font
					(size 1.27 1.27)
				)
				(justify mirror)
			)
		)
		(duplicate_pad_numbers_are_jumpers no)
		(fp_line
			(start -1.524 0.762)
			(end 1.524 0.762)
			(stroke
				(width 0.1524)
				(type default)
			)
			(layer "B.SilkS")
		)
		(fp_line
			(start 1.524 0.762)
			(end 1.524 -0.762)
			(stroke
				(width 0.1524)
				(type default)
			)
			(layer "B.SilkS")
		)
		(fp_line
			(start -1.524 -0.762)
			(end -1.524 0.762)
			(stroke
				(width 0.1524)
				(type default)
			)
			(layer "B.SilkS")
		)
		(fp_line
			(start 1.524 -0.762)
			(end -1.524 -0.762)
			(stroke
				(width 0.1524)
				(type default)
			)
			(layer "B.SilkS")
		)
		(fp_line
			(start -1.1049 0.724916)
			(end -1.1049 -0.724916)
			(stroke
				(width 0.1)
				(type default)
			)
			(layer "B.Fab")
		)
		(fp_line
			(start 1.1049 0.724916)
			(end -1.1049 0.724916)
			(stroke
				(width 0.1)
				(type default)
			)
			(layer "B.Fab")
		)
		(fp_line
			(start -1.1049 -0.724916)
			(end 1.1049 -0.724916)
			(stroke
				(width 0.1)
				(type default)
			)
			(layer "B.Fab")
		)
		(fp_line
			(start 1.1049 -0.724916)
			(end 1.1049 0.724916)
			(stroke
				(width 0.1)
				(type default)
			)
			(layer "B.Fab")
		)
		(pad "1" smd rect
			(at 0.889 0 270)
			(size 1.016 1.27)
			(layers "B.Cu" "B.Mask" "B.Paste")
			(net "P0V8_PEX2")
		)
		(pad "2" smd rect
			(at -0.889 0 270)
			(size 1.016 1.27)
			(layers "B.Cu" "B.Mask" "B.Paste")
			(net "GND")
		)
	)
	(footprint ""
		(layer "B.Cu")
		(at 290.89985 -303.499774 -90)
		(property "Reference" "C3280"
			(at 0 0 90)
			(layer "B.SilkS")
			(hide yes)
			(effects
				(font
					(size 1.27 1.27)
				)
				(justify mirror)
			)
		)
		(property "Value" ""
			(at 0 0 90)
			(layer "B.Fab")
			(effects
				(font
					(size 1.27 1.27)
				)
				(justify mirror)
			)
		)
		(duplicate_pad_numbers_are_jumpers no)
		(fp_line
			(start -0.299974 0.150114)
			(end 0.299974 0.150114)
			(stroke
				(width 0.1)
				(type default)
			)
			(layer "B.Fab")
		)
		(fp_line
			(start 0.299974 0.150114)
			(end 0.299974 -0.150114)
			(stroke
				(width 0.1)
				(type default)
			)
			(layer "B.Fab")
		)
		(fp_line
			(start -0.299974 -0.150114)
			(end -0.299974 0.150114)
			(stroke
				(width 0.1)
				(type default)
			)
			(layer "B.Fab")
		)
		(fp_line
			(start 0.299974 -0.150114)
			(end -0.299974 -0.150114)
			(stroke
				(width 0.1)
				(type default)
			)
			(layer "B.Fab")
		)
		(pad "1" smd rect
			(at 0.2667 0 90)
			(size 0.3048 0.381)
			(layers "B.Cu" "B.Mask" "B.Paste")
			(net "P1V25_PEX2")
		)
		(pad "2" smd rect
			(at -0.2667 0 90)
			(size 0.3048 0.381)
			(layers "B.Cu" "B.Mask" "B.Paste")
			(net "GND")
		)
	)
)
